(kicad_pcb
	(version 20260206)
	(generator "pcbnew")
	(generator_version "10.0")
	(general
		(thickness 1.6)
		(legacy_teardrops no)
	)
	(paper "A4")
	(title_block
		(title "9054_F0T_PDB_BD_GPU_F_V04_1213_1550_OCP.brd")
		(comment 1 "Grand Teton / footprints 399-403 of 608")
	)
	(layers
		(0 "F.Cu" signal "TOP")
		(4 "In1.Cu" signal "GND")
		(6 "In2.Cu" signal "IN1")
		(8 "In3.Cu" signal "GND1")
		(10 "In4.Cu" signal "VCC")
		(12 "In5.Cu" signal "VCC1")
		(14 "In6.Cu" signal "GND2")
		(16 "In7.Cu" signal "IN2")
		(18 "In8.Cu" signal "GND3")
		(2 "B.Cu" signal "BOTTOM")
		(9 "F.Adhes" user "F.Adhesive")
		(11 "B.Adhes" user "B.Adhesive")
		(13 "F.Paste" user "Package Geometry/Pastemask Top")
		(15 "B.Paste" user "Package Geometry/Pastemask Bottom")
		(5 "F.SilkS" user "Ref Des/Silkscreen Top")
		(7 "B.SilkS" user "Ref Des/Silkscreen Bottom")
		(1 "F.Mask" user "Board Geometry/Soldermask Top")
		(3 "B.Mask" user "Board Geometry/Soldermask Bottom")
		(17 "Dwgs.User" user "User.Drawings")
		(19 "Cmts.User" user "User.Comments")
		(21 "Eco1.User" user "User.Eco1")
		(23 "Eco2.User" user "User.Eco2")
		(25 "Edge.Cuts" user "Board Geometry/Outline")
		(27 "Margin" user)
		(31 "F.CrtYd" user "Package Geometry/Place Bound Top")
		(29 "B.CrtYd" user "Package Geometry/Place Bound Bottom")
		(35 "F.Fab" user "Ref Des/Assembly Top")
		(33 "B.Fab" user "Ref Des/Assembly Bottom")
	)
	(footprint ""
		(layer "B.Cu")
		(at 156.637736 -77.216 90)
		(property "Reference" "R5874"
			(at 0 0 90)
			(layer "B.SilkS")
			(hide yes)
			(effects
				(font
					(size 1.27 1.27)
				)
				(justify mirror)
			)
		)
		(property "Value" ""
			(at 0 0 90)
			(layer "B.Fab")
			(effects
				(font
					(size 1.27 1.27)
				)
				(justify mirror)
			)
		)
		(duplicate_pad_numbers_are_jumpers no)
		(fp_line
			(start 0.7874 -0.4064)
			(end -0.7874 -0.4064)
			(stroke
				(width 0.1524)
				(type default)
			)
			(layer "B.SilkS")
		)
		(fp_line
			(start -0.7874 -0.4064)
			(end -0.7874 0.4064)
			(stroke
				(width 0.1524)
				(type default)
			)
			(layer "B.SilkS")
		)
		(fp_line
			(start 0.7874 0.4064)
			(end 0.7874 -0.4064)
			(stroke
				(width 0.1524)
				(type default)
			)
			(layer "B.SilkS")
		)
		(fp_line
			(start -0.7874 0.4064)
			(end 0.7874 0.4064)
			(stroke
				(width 0.1524)
				(type default)
			)
			(layer "B.SilkS")
		)
		(fp_line
			(start 0.67945 -0.305054)
			(end 0.12065 -0.305054)
			(stroke
				(width 0.1)
				(type default)
			)
			(layer "B.Fab")
		)
		(fp_line
			(start 0.12065 -0.305054)
			(end 0.12065 -0.2794)
			(stroke
				(width 0.1)
				(type default)
			)
			(layer "B.Fab")
		)
		(fp_line
			(start -0.12065 -0.3048)
			(end -0.67945 -0.3048)
			(stroke
				(width 0.1)
				(type default)
			)
			(layer "B.Fab")
		)
		(fp_line
			(start -0.67945 -0.3048)
			(end -0.67945 0.3048)
			(stroke
				(width 0.1)
				(type default)
			)
			(layer "B.Fab")
		)
		(fp_line
			(start 0.12065 -0.2794)
			(end -0.12065 -0.2794)
			(stroke
				(width 0.1)
				(type default)
			)
			(layer "B.Fab")
		)
		(fp_line
			(start -0.12065 -0.2794)
			(end -0.12065 -0.3048)
			(stroke
				(width 0.1)
				(type default)
			)
			(layer "B.Fab")
		)
		(fp_line
			(start 0.12065 0.2794)
			(end 0.12065 0.3048)
			(stroke
				(width 0.1)
				(type default)
			)
			(layer "B.Fab")
		)
		(fp_line
			(start -0.120396 0.2794)
			(end 0.12065 0.2794)
			(stroke
				(width 0.1)
				(type default)
			)
			(layer "B.Fab")
		)
		(fp_line
			(start 0.67945 0.3048)
			(end 0.67945 -0.305054)
			(stroke
				(width 0.1)
				(type default)
			)
			(layer "B.Fab")
		)
		(fp_line
			(start 0.12065 0.3048)
			(end 0.67945 0.3048)
			(stroke
				(width 0.1)
				(type default)
			)
			(layer "B.Fab")
		)
		(fp_line
			(start -0.120396 0.3048)
			(end -0.120396 0.2794)
			(stroke
				(width 0.1)
				(type default)
			)
			(layer "B.Fab")
		)
		(fp_line
			(start -0.67945 0.3048)
			(end -0.120396 0.3048)
			(stroke
				(width 0.1)
				(type default)
			)
			(layer "B.Fab")
		)
		(pad "1" smd circle
			(at 0.40005 0 270)
			(size 0 0)
			(layers "B.Cu" "B.Mask" "B.Paste")
			(net "P52V_HS2_INTVCC")
		)
		(pad "2" smd circle
			(at -0.40005 0 270)
			(size 0 0)
			(layers "B.Cu" "B.Mask" "B.Paste")
			(net "P52V_HS2_ADR1")
		)
	)
	(footprint ""
		(layer "B.Cu")
		(at 184.4294 -52.832 90)
		(property "Reference" "PD12"
			(at 7.84733 2.6416 0)
			(unlocked yes)
			(layer "B.SilkS")
			(effects
				(font
					(size 0.7874 0.5842)
					(thickness 0.1524)
				)
				(justify left mirror)
			)
		)
		(property "Value" ""
			(at 0 0 90)
			(layer "B.Fab")
			(effects
				(font
					(size 1.27 1.27)
				)
				(justify mirror)
			)
		)
		(duplicate_pad_numbers_are_jumpers no)
		(fp_line
			(start 4.664456 -3.109976)
			(end -4.743704 -3.109976)
			(stroke
				(width 0.1524)
				(type default)
			)
			(layer "B.SilkS")
		)
		(fp_line
			(start -4.183126 -3.109976)
			(end -4.794504 -3.109976)
			(stroke
				(width 0.1524)
				(type default)
			)
			(layer "B.SilkS")
		)
		(fp_line
			(start -4.511802 -3.109976)
			(end -4.207002 -3.109976)
			(stroke
				(width 0.1524)
				(type default)
			)
			(layer "B.SilkS")
		)
		(fp_line
			(start -4.6101 -3.109976)
			(end -4.283202 -3.109976)
			(stroke
				(width 0.1524)
				(type default)
			)
			(layer "B.SilkS")
		)
		(fp_line
			(start -4.695444 -3.109976)
			(end -4.695444 3.109976)
			(stroke
				(width 0.1524)
				(type default)
			)
			(layer "B.SilkS")
		)
		(fp_line
			(start -4.70535 -3.109976)
			(end -4.70535 3.109976)
			(stroke
				(width 0.1524)
				(type default)
			)
			(layer "B.SilkS")
		)
		(fp_line
			(start -4.70535 -3.109976)
			(end -4.70535 3.109976)
			(stroke
				(width 0.1524)
				(type default)
			)
			(layer "B.SilkS")
		)
		(fp_line
			(start -4.70535 -3.109976)
			(end -4.70535 3.109976)
			(stroke
				(width 0.1524)
				(type default)
			)
			(layer "B.SilkS")
		)
		(fp_line
			(start -4.805426 -3.109976)
			(end -4.805426 3.109976)
			(stroke
				(width 0.1524)
				(type default)
			)
			(layer "B.SilkS")
		)
		(fp_line
			(start -4.932426 -3.109976)
			(end -4.932426 3.109976)
			(stroke
				(width 0.1524)
				(type default)
			)
			(layer "B.SilkS")
		)
		(fp_line
			(start -5.008626 -3.109976)
			(end -5.008626 3.109976)
			(stroke
				(width 0.1524)
				(type default)
			)
			(layer "B.SilkS")
		)
		(fp_line
			(start -5.110226 -3.109976)
			(end -5.110226 3.109976)
			(stroke
				(width 0.1524)
				(type default)
			)
			(layer "B.SilkS")
		)
		(fp_line
			(start -5.211826 -3.109976)
			(end -5.211826 3.109976)
			(stroke
				(width 0.1524)
				(type default)
			)
			(layer "B.SilkS")
		)
		(fp_line
			(start -5.262626 -3.109976)
			(end -5.262626 3.109976)
			(stroke
				(width 0.1524)
				(type default)
			)
			(layer "B.SilkS")
		)
		(fp_line
			(start -5.313426 -3.109976)
			(end -5.313426 3.109976)
			(stroke
				(width 0.1524)
				(type default)
			)
			(layer "B.SilkS")
		)
		(fp_line
			(start -5.4102 -3.109976)
			(end -4.783074 -3.109976)
			(stroke
				(width 0.1524)
				(type default)
			)
			(layer "B.SilkS")
		)
		(fp_line
			(start -5.4102 -1.9304)
			(end -5.4102 -3.109976)
			(stroke
				(width 0.1524)
				(type default)
			)
			(layer "B.SilkS")
		)
		(fp_line
			(start 0.508 -1.016)
			(end -0.762 0)
			(stroke
				(width 0.1524)
				(type default)
			)
			(layer "B.SilkS")
		)
		(fp_line
			(start 1.0668 0)
			(end 0.6096 0)
			(stroke
				(width 0.1524)
				(type default)
			)
			(layer "B.SilkS")
		)
		(fp_line
			(start -0.762 0)
			(end -1.2192 0)
			(stroke
				(width 0.1524)
				(type default)
			)
			(layer "B.SilkS")
		)
		(fp_line
			(start -0.762 0)
			(end 0.508 1.016)
			(stroke
				(width 0.1524)
				(type default)
			)
			(layer "B.SilkS")
		)
		(fp_line
			(start 0.508 1.016)
			(end 0.508 -1.016)
			(stroke
				(width 0.1524)
				(type default)
			)
			(layer "B.SilkS")
		)
		(fp_line
			(start -0.762 1.27)
			(end -0.762 -1.27)
			(stroke
				(width 0.1524)
				(type default)
			)
			(layer "B.SilkS")
		)
		(fp_line
			(start -4.715002 3.035554)
			(end -4.7117 2.984754)
			(stroke
				(width 0.1524)
				(type default)
			)
			(layer "B.SilkS")
		)
		(fp_line
			(start 4.664456 3.109976)
			(end 4.664456 -3.109976)
			(stroke
				(width 0.1524)
				(type default)
			)
			(layer "B.SilkS")
		)
		(fp_line
			(start -4.156202 3.109976)
			(end -4.183126 3.109976)
			(stroke
				(width 0.1524)
				(type default)
			)
			(layer "B.SilkS")
		)
		(fp_line
			(start -4.743704 3.109976)
			(end -4.6101 3.109976)
			(stroke
				(width 0.1524)
				(type default)
			)
			(layer "B.SilkS")
		)
		(fp_line
			(start -4.743704 3.109976)
			(end -5.4102 3.109976)
			(stroke
				(width 0.1524)
				(type default)
			)
			(layer "B.SilkS")
		)
		(fp_line
			(start -4.769104 3.109976)
			(end 4.664456 3.109976)
			(stroke
				(width 0.1524)
				(type default)
			)
			(layer "B.SilkS")
		)
		(fp_line
			(start -4.794504 3.109976)
			(end -3.554984 3.109976)
			(stroke
				(width 0.1524)
				(type default)
			)
			(layer "B.SilkS")
		)
		(fp_line
			(start -5.4102 3.109976)
			(end -5.4102 -1.0668)
			(stroke
				(width 0.1524)
				(type default)
			)
			(layer "B.SilkS")
		)
		(fp_line
			(start 4.065016 -3.109976)
			(end -4.065016 -3.109976)
			(stroke
				(width 0.1)
				(type default)
			)
			(layer "B.Fab")
		)
		(fp_line
			(start -4.065016 -3.109976)
			(end -4.065016 3.109976)
			(stroke
				(width 0.1)
				(type default)
			)
			(layer "B.Fab")
		)
		(fp_line
			(start 4.065016 3.109976)
			(end 4.065016 -3.109976)
			(stroke
				(width 0.1)
				(type default)
			)
			(layer "B.Fab")
		)
		(fp_line
			(start -4.065016 3.109976)
			(end 4.065016 3.109976)
			(stroke
				(width 0.1)
				(type default)
			)
			(layer "B.Fab")
		)
		(fp_text user "-"
			(at -8.001 0.19685 270)
			(unlocked yes)
			(layer "B.SilkS")
			(effects
				(font
					(size 1.905 1.4224)
					(thickness 0.1524)
				)
				(justify left mirror)
			)
		)
		(fp_text user "+"
			(at 5.9944 0.37465 270)
			(unlocked yes)
			(layer "B.SilkS")
			(effects
				(font
					(size 1.905 1.4224)
					(thickness 0.1524)
				)
				(justify left mirror)
			)
		)
		(fp_text user "+"
			(at 4.5974 0.24765 270)
			(unlocked yes)
			(layer "B.Fab")
			(effects
				(font
					(size 1.905 1.4224)
					(thickness 0.1524)
				)
				(justify left mirror)
			)
		)
		(fp_text user "-"
			(at -6.643624 0.40005 270)
			(unlocked yes)
			(layer "B.Fab")
			(effects
				(font
					(size 1.905 1.4224)
					(thickness 0.1524)
				)
				(justify left mirror)
			)
		)
		(pad "A" smd rect
			(at 3.299968 0 90)
			(size 2.413 3.302)
			(layers "B.Cu" "B.Mask" "B.Paste")
			(net "GND")
		)
		(pad "C" smd rect
			(at -3.299968 0 90)
			(size 2.413 3.302)
			(layers "B.Cu" "B.Mask" "B.Paste")
			(net "P52V_2_FUSE_1")
		)
	)
	(footprint ""
		(layer "B.Cu")
		(at 340.5124 -49.7586 90)
		(property "Reference" "PR26"
			(at 0 0 90)
			(layer "B.SilkS")
			(hide yes)
			(effects
				(font
					(size 1.27 1.27)
				)
				(justify mirror)
			)
		)
		(property "Value" ""
			(at 0 0 90)
			(layer "B.Fab")
			(effects
				(font
					(size 1.27 1.27)
				)
				(justify mirror)
			)
		)
		(duplicate_pad_numbers_are_jumpers no)
		(fp_line
			(start 0.7874 -0.4064)
			(end -0.7874 -0.4064)
			(stroke
				(width 0.1524)
				(type default)
			)
			(layer "B.SilkS")
		)
		(fp_line
			(start -0.7874 -0.4064)
			(end -0.7874 0.4064)
			(stroke
				(width 0.1524)
				(type default)
			)
			(layer "B.SilkS")
		)
		(fp_line
			(start 0.7874 0.4064)
			(end 0.7874 -0.4064)
			(stroke
				(width 0.1524)
				(type default)
			)
			(layer "B.SilkS")
		)
		(fp_line
			(start -0.7874 0.4064)
			(end 0.7874 0.4064)
			(stroke
				(width 0.1524)
				(type default)
			)
			(layer "B.SilkS")
		)
		(fp_line
			(start 0.67945 -0.305054)
			(end 0.12065 -0.305054)
			(stroke
				(width 0.1)
				(type default)
			)
			(layer "B.Fab")
		)
		(fp_line
			(start 0.12065 -0.305054)
			(end 0.12065 -0.2794)
			(stroke
				(width 0.1)
				(type default)
			)
			(layer "B.Fab")
		)
		(fp_line
			(start -0.12065 -0.3048)
			(end -0.67945 -0.3048)
			(stroke
				(width 0.1)
				(type default)
			)
			(layer "B.Fab")
		)
		(fp_line
			(start -0.67945 -0.3048)
			(end -0.67945 0.3048)
			(stroke
				(width 0.1)
				(type default)
			)
			(layer "B.Fab")
		)
		(fp_line
			(start 0.12065 -0.2794)
			(end -0.12065 -0.2794)
			(stroke
				(width 0.1)
				(type default)
			)
			(layer "B.Fab")
		)
		(fp_line
			(start -0.12065 -0.2794)
			(end -0.12065 -0.3048)
			(stroke
				(width 0.1)
				(type default)
			)
			(layer "B.Fab")
		)
		(fp_line
			(start 0.12065 0.2794)
			(end 0.12065 0.3048)
			(stroke
				(width 0.1)
				(type default)
			)
			(layer "B.Fab")
		)
		(fp_line
			(start -0.120396 0.2794)
			(end 0.12065 0.2794)
			(stroke
				(width 0.1)
				(type default)
			)
			(layer "B.Fab")
		)
		(fp_line
			(start 0.67945 0.3048)
			(end 0.67945 -0.305054)
			(stroke
				(width 0.1)
				(type default)
			)
			(layer "B.Fab")
		)
		(fp_line
			(start 0.12065 0.3048)
			(end 0.67945 0.3048)
			(stroke
				(width 0.1)
				(type default)
			)
			(layer "B.Fab")
		)
		(fp_line
			(start -0.120396 0.3048)
			(end -0.120396 0.2794)
			(stroke
				(width 0.1)
				(type default)
			)
			(layer "B.Fab")
		)
		(fp_line
			(start -0.67945 0.3048)
			(end -0.120396 0.3048)
			(stroke
				(width 0.1)
				(type default)
			)
			(layer "B.Fab")
		)
		(pad "1" smd rect
			(at 0.40005 0 90)
			(size 0.4572 0.508)
			(layers "B.Cu" "B.Mask" "B.Paste")
			(net "P52V_HS1_GATE_R1")
		)
		(pad "2" smd rect
			(at -0.40005 0 90)
			(size 0.4572 0.508)
			(layers "B.Cu" "B.Mask" "B.Paste")
			(net "P52V_HS1_4287_GATE_R")
		)
	)
	(footprint ""
		(layer "B.Cu")
		(at 449.199 -46.736 180)
		(property "Reference" "C103"
			(at 0 0 0)
			(layer "B.SilkS")
			(hide yes)
			(effects
				(font
					(size 1.27 1.27)
				)
				(justify mirror)
			)
		)
		(property "Value" ""
			(at 0 0 0)
			(layer "B.Fab")
			(effects
				(font
					(size 1.27 1.27)
				)
				(justify mirror)
			)
		)
		(duplicate_pad_numbers_are_jumpers no)
		(fp_line
			(start 0.7874 0.4064)
			(end 0.7874 -0.4064)
			(stroke
				(width 0.1524)
				(type default)
			)
			(layer "B.SilkS")
		)
		(fp_line
			(start 0.7874 -0.4064)
			(end -0.7874 -0.4064)
			(stroke
				(width 0.1524)
				(type default)
			)
			(layer "B.SilkS")
		)
		(fp_line
			(start -0.7874 0.4064)
			(end 0.7874 0.4064)
			(stroke
				(width 0.1524)
				(type default)
			)
			(layer "B.SilkS")
		)
		(fp_line
			(start -0.7874 -0.4064)
			(end -0.7874 0.4064)
			(stroke
				(width 0.1524)
				(type default)
			)
			(layer "B.SilkS")
		)
		(fp_line
			(start 0.67945 0.3048)
			(end 0.67945 -0.305054)
			(stroke
				(width 0.1)
				(type default)
			)
			(layer "B.Fab")
		)
		(fp_line
			(start 0.67945 -0.305054)
			(end 0.12065 -0.305054)
			(stroke
				(width 0.1)
				(type default)
			)
			(layer "B.Fab")
		)
		(fp_line
			(start 0.12065 0.3048)
			(end 0.67945 0.3048)
			(stroke
				(width 0.1)
				(type default)
			)
			(layer "B.Fab")
		)
		(fp_line
			(start 0.12065 0.2794)
			(end 0.12065 0.3048)
			(stroke
				(width 0.1)
				(type default)
			)
			(layer "B.Fab")
		)
		(fp_line
			(start 0.12065 -0.2794)
			(end -0.12065 -0.2794)
			(stroke
				(width 0.1)
				(type default)
			)
			(layer "B.Fab")
		)
		(fp_line
			(start 0.12065 -0.305054)
			(end 0.12065 -0.2794)
			(stroke
				(width 0.1)
				(type default)
			)
			(layer "B.Fab")
		)
		(fp_line
			(start -0.120396 0.3048)
			(end -0.120396 0.2794)
			(stroke
				(width 0.1)
				(type default)
			)
			(layer "B.Fab")
		)
		(fp_line
			(start -0.120396 0.2794)
			(end 0.12065 0.2794)
			(stroke
				(width 0.1)
				(type default)
			)
			(layer "B.Fab")
		)
		(fp_line
			(start -0.12065 -0.2794)
			(end -0.12065 -0.3048)
			(stroke
				(width 0.1)
				(type default)
			)
			(layer "B.Fab")
		)
		(fp_line
			(start -0.12065 -0.3048)
			(end -0.67945 -0.3048)
			(stroke
				(width 0.1)
				(type default)
			)
			(layer "B.Fab")
		)
		(fp_line
			(start -0.67945 0.3048)
			(end -0.120396 0.3048)
			(stroke
				(width 0.1)
				(type default)
			)
			(layer "B.Fab")
		)
		(fp_line
			(start -0.67945 -0.3048)
			(end -0.67945 0.3048)
			(stroke
				(width 0.1)
				(type default)
			)
			(layer "B.Fab")
		)
		(pad "1" smd circle
			(at 0.40005 0)
			(size 0 0)
			(layers "B.Cu" "B.Mask" "B.Paste")
			(net "P3V3_AUX")
		)
		(pad "2" smd circle
			(at -0.40005 0)
			(size 0 0)
			(layers "B.Cu" "B.Mask" "B.Paste")
			(net "GND")
		)
	)
	(footprint ""
		(layer "B.Cu")
		(at 154.351736 -60.198 90)
		(property "Reference" "PJ5"
			(at -2.18567 0.207264 0)
			(unlocked yes)
			(layer "B.SilkS")
			(effects
				(font
					(size 0.7874 0.5842)
					(thickness 0.1524)
				)
				(justify left mirror)
			)
		)
		(property "Value" ""
			(at 0 0 90)
			(layer "B.Fab")
			(effects
				(font
					(size 1.27 1.27)
				)
				(justify mirror)
			)
		)
		(duplicate_pad_numbers_are_jumpers no)
		(pad "1" smd circle
			(at 0.7493 0 180)
			(size 0 0)
			(layers "B.Cu" "B.Mask" "B.Paste")
			(net "GND1_FIELD_SIGNAL")
		)
		(pad "2" smd rect
			(at -0.7493 0)
			(size 0.7112 0.8128)
			(layers "B.Cu" "B.Mask" "B.Paste")
			(net "GND")
		)
		(zone
			(layer "B.Cu")
			(hatch none 0.5)
			(connect_pads
				(clearance 0)
			)
			(min_thickness 0.25)
			(keepout
				(tracks allowed)
				(vias not_allowed)
				(pads allowed)
				(copperpour not_allowed)
				(footprints allowed)
			)
			(placement
				(enabled no)
				(sheetname "")
			)
			(fill
				(thermal_gap 0.5)
				(thermal_bridge_width 0.5)
				(island_removal_mode 0)
			)
			(polygon
				(pts
					(xy 153.945336 -58.9915) (xy 154.762962 -58.9915) (xy 154.762962 -61.3791) (xy 153.945336 -61.3791)
				)
			)
		)
	)
)
